(kicad_pcb
	(version 20241229)
	(generator "pcbnew")
	(generator_version "9.0")
	(general
		(thickness 1.6296)
		(legacy_teardrops no)
	)
	(paper "A3")
	(title_block
		(title "Thunderbolt to 10GbE adapter")
		(date "2026-04-21")
		(rev "1.1.0")
		(company "Antmicro Ltd")
		(comment 1 "www.antmicro.com")
		(comment 9 "footprints 309-312 of 703")
	)
	(layers
		(0 "F.Cu" signal)
		(4 "In1.Cu" signal)
		(6 "In2.Cu" signal)
		(8 "In3.Cu" signal)
		(10 "In4.Cu" signal)
		(12 "In5.Cu" signal)
		(14 "In6.Cu" signal)
		(2 "B.Cu" signal)
		(9 "F.Adhes" user "F.Adhesive")
		(11 "B.Adhes" user "B.Adhesive")
		(13 "F.Paste" user)
		(15 "B.Paste" user)
		(5 "F.SilkS" user "F.Silkscreen")
		(7 "B.SilkS" user "B.Silkscreen")
		(1 "F.Mask" user)
		(3 "B.Mask" user)
		(17 "Dwgs.User" user "User.Drawings")
		(19 "Cmts.User" user "User.Comments")
		(21 "Eco1.User" user "User.Eco1")
		(23 "Eco2.User" user "User.Eco2")
		(25 "Edge.Cuts" user)
		(27 "Margin" user)
		(31 "F.CrtYd" user "F.Courtyard")
		(29 "B.CrtYd" user "B.Courtyard")
		(35 "F.Fab" user)
		(33 "B.Fab" user)
	)
	(footprint "antmicro-footprints:LED_0603_1608Metric_G"
		(layer "F.Cu")
		(at 116 139 90)
		(descr "LED SMD 0603 Green")
		(tags "LED SMD 0603 Green")
		(property "Reference" "D2"
			(at -0.75 3 90)
			(layer "F.SilkS")
			(effects
				(font
					(size 0.7 0.7)
					(thickness 0.15)
				)
				(justify left bottom)
			)
		)
		(property "Value" "LED_G_0603_LTST-C190GKT"
			(at -0.001 1.599 90)
			(layer "F.Fab")
			(effects
				(font
					(size 0.7 0.7)
					(thickness 0.15)
				)
				(justify left bottom)
			)
		)
		(property "Datasheet" "https://media.digikey.com/pdf/Data%20Sheets/Lite-On%20PDFs/LTST-C190GKT.pdf"
			(at 0 0 90)
			(layer "F.Fab")
			(hide yes)
			(effects
				(font
					(size 1.27 1.27)
					(thickness 0.15)
				)
			)
		)
		(property "Description" "LED, Green, SMD, 0603, 20 mA, 2.1 V, 569 nm"
			(at 0 0 90)
			(layer "F.Fab")
			(hide yes)
			(effects
				(font
					(size 1.27 1.27)
					(thickness 0.15)
				)
			)
		)
		(property "MPN" "LTST-C190GKT"
			(at 0 0 90)
			(unlocked yes)
			(layer "F.Fab")
			(hide yes)
			(effects
				(font
					(size 1 1)
					(thickness 0.15)
				)
			)
		)
		(property "Manufacturer" "Lite-On"
			(at 0 0 90)
			(unlocked yes)
			(layer "F.Fab")
			(hide yes)
			(effects
				(font
					(size 1 1)
					(thickness 0.15)
				)
			)
		)
		(property "Author" "Antmicro"
			(at 0 0 90)
			(unlocked yes)
			(layer "F.Fab")
			(hide yes)
			(effects
				(font
					(size 1 1)
					(thickness 0.15)
				)
			)
		)
		(property "License" "Apache-2.0"
			(at 0 0 90)
			(unlocked yes)
			(layer "F.Fab")
			(hide yes)
			(effects
				(font
					(size 1 1)
					(thickness 0.15)
				)
			)
		)
		(property "Color" "Green"
			(at 0 0 90)
			(unlocked yes)
			(layer "F.Fab")
			(hide yes)
			(effects
				(font
					(size 1 1)
					(thickness 0.15)
				)
			)
		)
		(sheetname "/USB-C connector/")
		(sheetfile "USB-C_connector.kicad_sch")
		(attr smd)
		(fp_line
			(start 0.22 -0.35)
			(end -0.22 -0.35)
			(stroke
				(width 0.15)
				(type solid)
			)
			(layer "F.SilkS")
		)
		(fp_line
			(start -1.18 -0.319)
			(end -1.18 0.321)
			(stroke
				(width 0.15)
				(type solid)
			)
			(layer "F.SilkS")
		)
		(fp_line
			(start 0.105328 0.001008)
			(end 0.24 0.001)
			(stroke
				(width 0.1)
				(type solid)
			)
			(layer "F.SilkS")
		)
		(fp_line
			(start -0.094672 0.001008)
			(end 0.105328 -0.198992)
			(stroke
				(width 0.1)
				(type solid)
			)
			(layer "F.SilkS")
		)
		(fp_line
			(start -0.094672 0.001008)
			(end -0.24 0.001008)
			(stroke
				(width 0.1)
				(type solid)
			)
			(layer "F.SilkS")
		)
		(fp_line
			(start 0.105328 0.201008)
			(end 0.105328 -0.198992)
			(stroke
				(width 0.1)
				(type solid)
			)
			(layer "F.SilkS")
		)
		(fp_line
			(start 0.105328 0.201008)
			(end -0.094672 0.001008)
			(stroke
				(width 0.1)
				(type solid)
			)
			(layer "F.SilkS")
		)
		(fp_line
			(start -0.094672 0.201008)
			(end -0.094672 -0.198992)
			(stroke
				(width 0.1)
				(type solid)
			)
			(layer "F.SilkS")
		)
		(fp_line
			(start 0.22 0.35)
			(end -0.22 0.35)
			(stroke
				(width 0.15)
				(type solid)
			)
			(layer "F.SilkS")
		)
		(fp_rect
			(start 1.25 0.65)
			(end -1.25 -0.65)
			(stroke
				(width 0.05)
				(type solid)
			)
			(fill no)
			(layer "F.CrtYd")
		)
		(fp_line
			(start 0.201 -0.202)
			(end -0.101 0)
			(stroke
				(width 0.15)
				(type solid)
			)
			(layer "F.Fab")
		)
		(fp_line
			(start -0.199 -0.202)
			(end -0.199 0.1)
			(stroke
				(width 0.15)
				(type solid)
			)
			(layer "F.Fab")
		)
		(fp_line
			(start 0.599 0)
			(end 0.201 0)
			(stroke
				(width 0.15)
				(type solid)
			)
			(layer "F.Fab")
		)
		(fp_line
			(start 0.201 0)
			(end 0.201 -0.202)
			(stroke
				(width 0.15)
				(type solid)
			)
			(layer "F.Fab")
		)
		(fp_line
			(start -0.101 0)
			(end 0.201 0.2)
			(stroke
				(width 0.15)
				(type solid)
			)
			(layer "F.Fab")
		)
		(fp_line
			(start -0.199 0)
			(end -0.597 0)
			(stroke
				(width 0.15)
				(type solid)
			)
			(layer "F.Fab")
		)
		(fp_line
			(start 0.201 0.2)
			(end 0.201 0)
			(stroke
				(width 0.15)
				(type solid)
			)
			(layer "F.Fab")
		)
		(fp_line
			(start -0.199 0.2)
			(end -0.199 0.1)
			(stroke
				(width 0.15)
				(type solid)
			)
			(layer "F.Fab")
		)
		(fp_rect
			(start 0.848 0.4)
			(end -0.85 -0.402)
			(stroke
				(width 0.15)
				(type solid)
			)
			(fill no)
			(layer "F.Fab")
		)
		(fp_text user "License: Apache-2.0"
			(at -1.4224 3.599 90)
			(layer "F.Fab")
			(effects
				(font
					(size 0.7 0.7)
					(thickness 0.15)
				)
				(justify left bottom)
			)
		)
		(fp_text user "Author: Antmicro"
			(at -1.4224 4.799 90)
			(layer "F.Fab")
			(effects
				(font
					(size 0.7 0.7)
					(thickness 0.15)
				)
				(justify left bottom)
			)
		)
		(fp_text user "${REFERENCE}"
			(at -1.4224 5.999 90)
			(layer "F.Fab")
			(effects
				(font
					(size 0.7 0.7)
					(thickness 0.15)
				)
				(justify left bottom)
			)
		)
		(pad "1" smd roundrect
			(at -0.7 0 270)
			(size 0.8 1)
			(layers "F.Cu" "F.Mask" "F.Paste")
			(roundrect_rratio 0.2)
			(net 23 "GND")
			(pinfunction "C")
			(pintype "passive")
		)
		(pad "2" smd roundrect
			(at 0.7 0 270)
			(size 0.8 1)
			(layers "F.Cu" "F.Mask" "F.Paste")
			(roundrect_rratio 0.2)
			(net 164 "Net-(D2-A)")
			(pinfunction "A")
			(pintype "passive")
		)
	)
	(footprint "antmicro-footprints:R_0402_1005Metric"
		(layer "F.Cu")
		(at 164 79.4 180)
		(descr "Resistor SMD 0402")
		(tags "resistor SMD 0402")
		(property "Reference" "R205"
			(at 1 -6.4 180)
			(layer "F.SilkS")
			(effects
				(font
					(size 0.7 0.7)
					(thickness 0.15)
				)
				(justify left bottom)
			)
		)
		(property "Value" "R_0R_0402"
			(at -1.011843 1.772047 180)
			(layer "F.Fab")
			(effects
				(font
					(size 0.7 0.7)
					(thickness 0.15)
				)
				(justify left bottom)
			)
		)
		(property "Datasheet" "https://industrial.panasonic.com/cdbs/www-data/pdf/RDA0000/AOA0000C301.pdf"
			(at 0 0 180)
			(layer "F.Fab")
			(hide yes)
			(effects
				(font
					(size 1.27 1.27)
					(thickness 0.15)
				)
			)
		)
		(property "Description" "SMD Chip Resistor, Jumper, 0 ohm, 100 mW, 0402 [1005 Metric], Thick Film, General Purpose"
			(at 0 0 180)
			(layer "F.Fab")
			(hide yes)
			(effects
				(font
					(size 1.27 1.27)
					(thickness 0.15)
				)
			)
		)
		(property "MPN" "ERJ2GE0R00X"
			(at 0 0 180)
			(unlocked yes)
			(layer "F.Fab")
			(hide yes)
			(effects
				(font
					(size 1 1)
					(thickness 0.15)
				)
			)
		)
		(property "Manufacturer" "Panasonic"
			(at 0 0 180)
			(unlocked yes)
			(layer "F.Fab")
			(hide yes)
			(effects
				(font
					(size 1 1)
					(thickness 0.15)
				)
			)
		)
		(property "License" "Apache-2.0"
			(at 0 0 180)
			(unlocked yes)
			(layer "F.Fab")
			(hide yes)
			(effects
				(font
					(size 1 1)
					(thickness 0.15)
				)
			)
		)
		(property "Author" "Antmicro"
			(at 0 0 180)
			(unlocked yes)
			(layer "F.Fab")
			(hide yes)
			(effects
				(font
					(size 1 1)
					(thickness 0.15)
				)
			)
		)
		(property "Val" "0R"
			(at 0 0 180)
			(unlocked yes)
			(layer "F.Fab")
			(hide yes)
			(effects
				(font
					(size 1 1)
					(thickness 0.15)
				)
			)
		)
		(property "Tolerance" "~"
			(at 0 0 180)
			(unlocked yes)
			(layer "F.Fab")
			(hide yes)
			(effects
				(font
					(size 1 1)
					(thickness 0.15)
				)
			)
		)
		(property "Current" "1A"
			(at 0 0 180)
			(unlocked yes)
			(layer "F.Fab")
			(hide yes)
			(effects
				(font
					(size 1 1)
					(thickness 0.15)
				)
			)
		)
		(sheetname "/X710-AT2 10GbE/")
		(sheetfile "x710-at2-10gbe.kicad_sch")
		(attr smd)
		(fp_rect
			(start -0.925 -0.47)
			(end 0.925 0.47)
			(stroke
				(width 0.05)
				(type default)
			)
			(fill no)
			(layer "F.CrtYd")
		)
		(fp_rect
			(start -0.5 -0.25)
			(end 0.5 0.25)
			(stroke
				(width 0.15)
				(type solid)
			)
			(fill no)
			(layer "F.Fab")
		)
		(fp_text user "License: Apache-2.0"
			(at -0.95 5.169 180)
			(layer "F.Fab")
			(effects
				(font
					(size 0.7 0.7)
					(thickness 0.15)
				)
				(justify left bottom)
			)
		)
		(fp_text user "${REFERENCE}"
			(at -0.95 3.168 180)
			(layer "F.Fab")
			(effects
				(font
					(size 0.7 0.7)
					(thickness 0.15)
				)
				(justify left bottom)
			)
		)
		(fp_text user "Author: Antmicro"
			(at -0.95 4.169 180)
			(layer "F.Fab")
			(effects
				(font
					(size 0.7 0.7)
					(thickness 0.15)
				)
				(justify left bottom)
			)
		)
		(pad "1" smd roundrect
			(at -0.48 0 180)
			(size 0.59 0.64)
			(layers "F.Cu" "F.Mask" "F.Paste")
			(roundrect_rratio 0.25)
			(net 23 "GND")
			(pintype "passive")
		)
		(pad "2" smd roundrect
			(at 0.48 0 180)
			(size 0.59 0.64)
			(layers "F.Cu" "F.Mask" "F.Paste")
			(roundrect_rratio 0.25)
			(net 130 "/X710-AT2 10GbE/TPIN_3")
			(pintype "passive")
		)
	)
	(footprint "antmicro-footprints:C_0603_1608Metric"
		(layer "F.Cu")
		(at 138.45 120.15 -90)
		(descr "Capacitor SMD 0603")
		(tags "capacitor 0603")
		(property "Reference" "C94"
			(at -1.35 -0.55 270)
			(layer "F.SilkS")
			(effects
				(font
					(size 0.7 0.7)
					(thickness 0.15)
				)
				(justify left bottom)
			)
		)
		(property "Value" "C_22u_0603"
			(at -1.42757 1.770288 270)
			(layer "F.Fab")
			(effects
				(font
					(size 0.7 0.7)
					(thickness 0.15)
				)
				(justify left bottom)
			)
		)
		(property "Datasheet" "https://www.murata.com/products/productdetail?partno=GRM188R60J226MEA0%23"
			(at 0 0 270)
			(layer "F.Fab")
			(hide yes)
			(effects
				(font
					(size 1.27 1.27)
					(thickness 0.15)
				)
			)
		)
		(property "Description" "SMD Multilayer Ceramic Capacitor, 22 µF, 6.3 V, 0603 [1608 Metric], ± 20%, X5R, GRM Series"
			(at 0 0 270)
			(layer "F.Fab")
			(hide yes)
			(effects
				(font
					(size 1.27 1.27)
					(thickness 0.15)
				)
			)
		)
		(property "MPN" "GRM188R60J226MEA0D"
			(at 0 0 270)
			(unlocked yes)
			(layer "F.Fab")
			(hide yes)
			(effects
				(font
					(size 1 1)
					(thickness 0.15)
				)
			)
		)
		(property "Manufacturer" "Murata"
			(at 0 0 270)
			(unlocked yes)
			(layer "F.Fab")
			(hide yes)
			(effects
				(font
					(size 1 1)
					(thickness 0.15)
				)
			)
		)
		(property "License" "Apache-2.0"
			(at 0 0 270)
			(unlocked yes)
			(layer "F.Fab")
			(hide yes)
			(effects
				(font
					(size 1 1)
					(thickness 0.15)
				)
			)
		)
		(property "Val" "22u"
			(at 0 0 270)
			(unlocked yes)
			(layer "F.Fab")
			(hide yes)
			(effects
				(font
					(size 1 1)
					(thickness 0.15)
				)
			)
		)
		(property "Voltage" ""
			(at 0 0 270)
			(unlocked yes)
			(layer "F.Fab")
			(hide yes)
			(effects
				(font
					(size 1 1)
					(thickness 0.15)
				)
			)
		)
		(property "Dielectric" ""
			(at 0 0 270)
			(unlocked yes)
			(layer "F.Fab")
			(hide yes)
			(effects
				(font
					(size 1 1)
					(thickness 0.15)
				)
			)
		)
		(property "Author" "Antmicro"
			(at 0 0 270)
			(unlocked yes)
			(layer "F.Fab")
			(hide yes)
			(effects
				(font
					(size 1 1)
					(thickness 0.15)
				)
			)
		)
		(sheetname "/TB Controller - Power/")
		(sheetfile "tb-power.kicad_sch")
		(attr smd)
		(fp_line
			(start -0.15 0.4)
			(end 0.15 0.4)
			(stroke
				(width 0.15)
				(type solid)
			)
			(layer "F.SilkS")
		)
		(fp_line
			(start -0.15 -0.4)
			(end 0.15 -0.4)
			(stroke
				(width 0.15)
				(type solid)
			)
			(layer "F.SilkS")
		)
		(fp_rect
			(start -1.25 -0.65)
			(end 1.25 0.65)
			(stroke
				(width 0.05)
				(type solid)
			)
			(fill no)
			(layer "F.CrtYd")
		)
		(fp_rect
			(start -0.8 -0.4)
			(end 0.8 0.4)
			(stroke
				(width 0.15)
				(type solid)
			)
			(fill no)
			(layer "F.Fab")
		)
		(fp_text user "License: Apache-2.0"
			(at -1.682 5.895 270)
			(layer "F.Fab")
			(effects
				(font
					(size 0.7 0.7)
					(thickness 0.15)
				)
				(justify left bottom)
			)
		)
		(fp_text user "Author: Antmicro"
			(at -1.682 4.894 270)
			(layer "F.Fab")
			(effects
				(font
					(size 0.7 0.7)
					(thickness 0.15)
				)
				(justify left bottom)
			)
		)
		(fp_text user "${REFERENCE}"
			(at -1.682 3.895 270)
			(layer "F.Fab")
			(effects
				(font
					(size 0.7 0.7)
					(thickness 0.15)
				)
				(justify left bottom)
			)
		)
		(pad "1" smd roundrect
			(at -0.7 0 270)
			(size 0.8 1)
			(layers "F.Cu" "F.Mask" "F.Paste")
			(roundrect_rratio 0.2)
			(net 23 "GND")
			(pintype "passive")
		)
		(pad "2" smd roundrect
			(at 0.7 0 270)
			(size 0.8 1)
			(layers "F.Cu" "F.Mask" "F.Paste")
			(roundrect_rratio 0.2)
			(net 68 "/TB Controller - Power/VCC_0P9")
			(pintype "passive")
		)
	)
	(footprint "antmicro-footprints:C_0603_1608Metric"
		(layer "F.Cu")
		(at 165.305 93.575 180)
		(descr "Capacitor SMD 0603")
		(tags "capacitor 0603")
		(property "Reference" "C181"
			(at -7.695 0 180)
			(layer "F.SilkS")
			(effects
				(font
					(size 0.7 0.7)
					(thickness 0.15)
				)
			)
		)
		(property "Value" "C_10u_10V_X7R_0603"
			(at -1.42757 1.770288 180)
			(layer "F.Fab")
			(effects
				(font
					(size 0.7 0.7)
					(thickness 0.15)
				)
				(justify left bottom)
			)
		)
		(property "Datasheet" "https://www.murata.com/products/productdetail?partno=GRM188Z71A106KA73%23"
			(at 0 0 180)
			(layer "F.Fab")
			(hide yes)
			(effects
				(font
					(size 1.27 1.27)
					(thickness 0.15)
				)
			)
		)
		(property "Description" "SMD Multilayer Ceramic Capacitor,  10µF, 10V, 0603, ±10%, X7R"
			(at 0 0 180)
			(layer "F.Fab")
			(hide yes)
			(effects
				(font
					(size 1.27 1.27)
					(thickness 0.15)
				)
			)
		)
		(property "MPN" "GRM188Z71A106KA73D"
			(at 0 0 180)
			(unlocked yes)
			(layer "F.Fab")
			(hide yes)
			(effects
				(font
					(size 1 1)
					(thickness 0.15)
				)
			)
		)
		(property "Val" "10u"
			(at 0 0 180)
			(unlocked yes)
			(layer "F.Fab")
			(hide yes)
			(effects
				(font
					(size 1 1)
					(thickness 0.15)
				)
			)
		)
		(property "Voltage" "10V"
			(at 0 0 180)
			(unlocked yes)
			(layer "F.Fab")
			(hide yes)
			(effects
				(font
					(size 1 1)
					(thickness 0.15)
				)
			)
		)
		(property "Dielectric" "X7R"
			(at 0 0 180)
			(unlocked yes)
			(layer "F.Fab")
			(hide yes)
			(effects
				(font
					(size 1 1)
					(thickness 0.15)
				)
			)
		)
		(property "Manufacturer" "Murata"
			(at 0 0 180)
			(unlocked yes)
			(layer "F.Fab")
			(hide yes)
			(effects
				(font
					(size 1 1)
					(thickness 0.15)
				)
			)
		)
		(property "License" "Apache-2.0"
			(at 0 0 180)
			(unlocked yes)
			(layer "F.Fab")
			(hide yes)
			(effects
				(font
					(size 1 1)
					(thickness 0.15)
				)
			)
		)
		(property "Author" "Antmicro"
			(at 0 0 180)
			(unlocked yes)
			(layer "F.Fab")
			(hide yes)
			(effects
				(font
					(size 1 1)
					(thickness 0.15)
				)
			)
		)
		(sheetname "/X710-AT2 power/")
		(sheetfile "x710-at2-power.kicad_sch")
		(attr smd)
		(fp_line
			(start -0.15 0.4)
			(end 0.15 0.4)
			(stroke
				(width 0.15)
				(type solid)
			)
			(layer "F.SilkS")
		)
		(fp_line
			(start -0.15 -0.4)
			(end 0.15 -0.4)
			(stroke
				(width 0.15)
				(type solid)
			)
			(layer "F.SilkS")
		)
		(fp_rect
			(start -1.25 -0.65)
			(end 1.25 0.65)
			(stroke
				(width 0.05)
				(type solid)
			)
			(fill no)
			(layer "F.CrtYd")
		)
		(fp_rect
			(start -0.8 -0.4)
			(end 0.8 0.4)
			(stroke
				(width 0.15)
				(type solid)
			)
			(fill no)
			(layer "F.Fab")
		)
		(fp_text user "Author: Antmicro"
			(at -1.682 4.894 180)
			(layer "F.Fab")
			(effects
				(font
					(size 0.7 0.7)
					(thickness 0.15)
				)
				(justify left bottom)
			)
		)
		(fp_text user "License: Apache-2.0"
			(at -1.682 5.895 180)
			(layer "F.Fab")
			(effects
				(font
					(size 0.7 0.7)
					(thickness 0.15)
				)
				(justify left bottom)
			)
		)
		(fp_text user "${REFERENCE}"
			(at -1.682 3.895 180)
			(layer "F.Fab")
			(effects
				(font
					(size 0.7 0.7)
					(thickness 0.15)
				)
				(justify left bottom)
			)
		)
		(pad "1" smd roundrect
			(at -0.7 0 180)
			(size 0.8 1)
			(layers "F.Cu" "F.Mask" "F.Paste")
			(roundrect_rratio 0.2)
			(net 23 "GND")
			(pintype "passive")
		)
		(pad "2" smd roundrect
			(at 0.7 0 180)
			(size 0.8 1)
			(layers "F.Cu" "F.Mask" "F.Paste")
			(roundrect_rratio 0.2)
			(net 14 "P1_AVDDL")
			(pintype "passive")
		)
	)
)
